(kicad_pcb
	(version 20260206)
	(generator "pcbnew")
	(generator_version "10.0")
	(general
		(thickness 1.6)
		(legacy_teardrops no)
	)
	(paper "A4")
	(title_block
		(title "Bryce Canyon_F.DPB_16315-1-OCP.brd")
		(comment 1 "Bryce Canyon / footprints 1946-1950 of 2223")
	)
	(layers
		(0 "F.Cu" signal "TOP")
		(4 "In1.Cu" signal "L2GND")
		(6 "In2.Cu" signal "L3")
		(8 "In3.Cu" signal "L4GND")
		(10 "In4.Cu" signal "L5")
		(12 "In5.Cu" signal "L6VCC")
		(14 "In6.Cu" signal "L7VCC")
		(16 "In7.Cu" signal "L8")
		(18 "In8.Cu" signal "L9GND")
		(20 "In9.Cu" signal "L10")
		(22 "In10.Cu" signal "L11GND")
		(2 "B.Cu" signal "BOTTOM")
		(9 "F.Adhes" user "F.Adhesive")
		(11 "B.Adhes" user "B.Adhesive")
		(13 "F.Paste" user "Package Geometry/Pastemask Top")
		(15 "B.Paste" user "Package Geometry/Pastemask Bottom")
		(5 "F.SilkS" user "Ref Des/Silkscreen Top")
		(7 "B.SilkS" user "Ref Des/Silkscreen Bottom")
		(1 "F.Mask" user "Board Geometry/Soldermask Top")
		(3 "B.Mask" user "Board Geometry/Soldermask Bottom")
		(17 "Dwgs.User" user "User.Drawings")
		(19 "Cmts.User" user "User.Comments")
		(21 "Eco1.User" user "User.Eco1")
		(23 "Eco2.User" user "User.Eco2")
		(25 "Edge.Cuts" user "Board Geometry/Outline")
		(27 "Margin" user)
		(31 "F.CrtYd" user "Package Geometry/Place Bound Top")
		(29 "B.CrtYd" user "Package Geometry/Place Bound Bottom")
		(35 "F.Fab" user "Ref Des/Assembly Top")
		(33 "B.Fab" user "Ref Des/Assembly Bottom")
	)
	(footprint ""
		(layer "F.Cu")
		(at 339.628734 -27.23769)
		(property "Reference" "U19"
			(at 0 0 0)
			(layer "F.SilkS")
			(hide yes)
			(effects
				(font
					(size 1.27 1.27)
				)
			)
		)
		(property "Value" "TCA9555PWR-GP"
			(at 0 -6.9342 0)
			(unlocked yes)
			(layer "F.Fab")
			(hide yes)
			(effects
				(font
					(size 1.016 1.016)
					(thickness 0.1524)
				)
			)
		)
		(property "Device Type" "TSOIC24H48"
			(at 0 -8.5852 0)
			(unlocked yes)
			(layer "F.Fab")
			(hide yes)
			(effects
				(font
					(size 1.016 1.016)
					(thickness 0.1524)
				)
			)
		)
		(duplicate_pad_numbers_are_jumpers no)
		(fp_line
			(start -4.2291 -1.397)
			(end 3.81 -1.397)
			(stroke
				(width 0.1524)
				(type default)
			)
			(layer "F.SilkS")
		)
		(fp_line
			(start -4.2291 -0.8001)
			(end -3.429 0)
			(stroke
				(width 0.1524)
				(type default)
			)
			(layer "F.SilkS")
		)
		(fp_line
			(start -4.2291 3.937)
			(end -4.2291 -1.397)
			(stroke
				(width 0.1524)
				(type default)
			)
			(layer "F.SilkS")
		)
		(fp_line
			(start -4.22656 3.81)
			(end -4.2291 1.397)
			(stroke
				(width 0.508)
				(type default)
			)
			(layer "F.SilkS")
		)
		(fp_line
			(start -3.429 0)
			(end -4.2291 0.8001)
			(stroke
				(width 0.1524)
				(type default)
			)
			(layer "F.SilkS")
		)
		(fp_line
			(start 3.81 -1.397)
			(end 3.81 1.397)
			(stroke
				(width 0.1524)
				(type default)
			)
			(layer "F.SilkS")
		)
		(fp_line
			(start 3.81 1.397)
			(end -4.2291 1.397)
			(stroke
				(width 0.1524)
				(type default)
			)
			(layer "F.SilkS")
		)
		(fp_poly
			(pts
				(xy -3.90652 -1.8542) (xy 3.90652 -1.8542) (xy 3.90652 1.8542) (xy -3.90652 1.8542)
			)
			(stroke
				(width 0)
				(type default)
			)
			(fill yes)
			(layer "F.SilkS")
		)
		(fp_poly
			(pts
				(xy -4.2164 3.81) (xy 4.2164 3.81) (xy 4.22656 -3.81) (xy -4.2164 -3.81)
			)
			(stroke
				(width 0)
				(type default)
			)
			(fill no)
			(layer "F.CrtYd")
		)
		(fp_poly
			(pts
				(xy -4.22656 -3.81) (xy 4.22656 -3.81) (xy 4.22656 3.81) (xy -4.22656 3.81)
			)
			(stroke
				(width 0)
				(type default)
			)
			(fill no)
			(layer "F.Fab")
		)
		(pad "1" smd rect
			(at -3.57632 2.8194)
			(size 0.3556 1.524)
			(layers "F.Cu" "F.Mask" "F.Paste")
			(net "BMC_B_MISC_ALERT_N")
		)
		(pad "2" smd rect
			(at -2.92608 2.8194)
			(size 0.3556 1.524)
			(layers "F.Cu" "F.Mask" "F.Paste")
			(net "IO_EXP11_A1")
		)
		(pad "3" smd rect
			(at -2.27584 2.8194)
			(size 0.3556 1.524)
			(layers "F.Cu" "F.Mask" "F.Paste")
			(net "IO_EXP11_A2")
		)
		(pad "4" smd rect
			(at -1.6256 2.8194)
			(size 0.3556 1.524)
			(layers "F.Cu" "F.Mask" "F.Paste")
			(net "COMP_B_INS_N")
		)
		(pad "5" smd rect
			(at -0.97536 2.8194)
			(size 0.3556 1.524)
			(layers "F.Cu" "F.Mask" "F.Paste")
			(net "FAN_0_INS_N")
		)
		(pad "6" smd rect
			(at -0.32512 2.8194)
			(size 0.3556 1.524)
			(layers "F.Cu" "F.Mask" "F.Paste")
			(net "FAN_1_INS_N")
		)
		(pad "7" smd rect
			(at 0.32512 2.8194)
			(size 0.3556 1.524)
			(layers "F.Cu" "F.Mask" "F.Paste")
			(net "FAN_2_INS_N")
		)
		(pad "8" smd rect
			(at 0.97536 2.8194)
			(size 0.3556 1.524)
			(layers "F.Cu" "F.Mask" "F.Paste")
			(net "FAN_3_INS_N")
		)
		(pad "9" smd rect
			(at 1.6256 2.8194)
			(size 0.3556 1.524)
			(layers "F.Cu" "F.Mask" "F.Paste")
			(net "IOM_A_INS_N")
		)
		(pad "10" smd rect
			(at 2.27584 2.8194)
			(size 0.3556 1.524)
			(layers "F.Cu" "F.Mask" "F.Paste")
			(net "SCC_A_INS_N")
		)
		(pad "11" smd rect
			(at 2.92608 2.8194)
			(size 0.3556 1.524)
			(layers "F.Cu" "F.Mask" "F.Paste")
			(net "SCC_B_INS_N")
		)
		(pad "12" smd rect
			(at 3.57632 2.8194)
			(size 0.3556 1.524)
			(layers "F.Cu" "F.Mask" "F.Paste")
			(net "GND")
		)
		(pad "13" smd rect
			(at 3.57632 -2.8194)
			(size 0.3556 1.524)
			(layers "F.Cu" "F.Mask" "F.Paste")
			(net "SCC_B_TYPE_0")
		)
		(pad "14" smd rect
			(at 2.92608 -2.8194)
			(size 0.3556 1.524)
			(layers "F.Cu" "F.Mask" "F.Paste")
			(net "SCC_B_TYPE_1")
		)
		(pad "15" smd rect
			(at 2.27584 -2.8194)
			(size 0.3556 1.524)
			(layers "F.Cu" "F.Mask" "F.Paste")
			(net "SCC_B_TYPE_2")
		)
		(pad "16" smd rect
			(at 1.6256 -2.8194)
			(size 0.3556 1.524)
			(layers "F.Cu" "F.Mask" "F.Paste")
			(net "SCC_B_TYPE_3")
		)
		(pad "17" smd rect
			(at 0.97536 -2.8194)
			(size 0.3556 1.524)
			(layers "F.Cu" "F.Mask" "F.Paste")
			(net "SCC_B_STBY_PGOOD")
		)
		(pad "18" smd rect
			(at 0.32512 -2.8194)
			(size 0.3556 1.524)
			(layers "F.Cu" "F.Mask" "F.Paste")
			(net "SCC_B_FULL_PGOOD")
		)
		(pad "19" smd rect
			(at -0.32512 -2.8194)
			(size 0.3556 1.524)
			(layers "F.Cu" "F.Mask" "F.Paste")
			(net "COMP_B_PGOOD")
		)
		(pad "20" smd rect
			(at -0.97536 -2.8194)
			(size 0.3556 1.524)
			(layers "F.Cu" "F.Mask" "F.Paste")
			(net "DRAWER_CLOSED_N")
		)
		(pad "21" smd rect
			(at -1.6256 -2.8194)
			(size 0.3556 1.524)
			(layers "F.Cu" "F.Mask" "F.Paste")
			(net "IO_EXP11_A0")
		)
		(pad "22" smd rect
			(at -2.27584 -2.8194)
			(size 0.3556 1.524)
			(layers "F.Cu" "F.Mask" "F.Paste")
			(net "IO_EXP11_SCL")
		)
		(pad "23" smd rect
			(at -2.92608 -2.8194)
			(size 0.3556 1.524)
			(layers "F.Cu" "F.Mask" "F.Paste")
			(net "IO_EXP11_SDA")
		)
		(pad "24" smd rect
			(at -3.57632 -2.8194)
			(size 0.3556 1.524)
			(layers "F.Cu" "F.Mask" "F.Paste")
			(net "P3V3_STBY_B")
		)
	)
	(footprint ""
		(layer "F.Cu")
		(at 117.646196 -48.554894 90)
		(property "Reference" "R763"
			(at 0 0 90)
			(layer "F.SilkS")
			(hide yes)
			(effects
				(font
					(size 1.27 1.27)
				)
			)
		)
		(property "Value" "4K7R2J-2-GP"
			(at 0.064008 -3.993896 90)
			(unlocked yes)
			(layer "F.Fab")
			(hide yes)
			(effects
				(font
					(size 1.016 1.016)
					(thickness 0.1524)
				)
			)
		)
		(property "Device Type" "R402H16"
			(at 0.064008 -5.517896 90)
			(unlocked yes)
			(layer "F.Fab")
			(hide yes)
			(effects
				(font
					(size 1.016 1.016)
					(thickness 0.1524)
				)
			)
		)
		(duplicate_pad_numbers_are_jumpers no)
		(fp_line
			(start 0.508 -0.9398)
			(end -0.508 -0.9398)
			(stroke
				(width 0.1524)
				(type default)
			)
			(layer "F.SilkS")
		)
		(fp_line
			(start -0.508 -0.9398)
			(end -0.508 0.9398)
			(stroke
				(width 0.1524)
				(type default)
			)
			(layer "F.SilkS")
		)
		(fp_rect
			(start -0.508 0.9398)
			(end 0.508 -0.9398)
			(stroke
				(width 0)
				(type default)
			)
			(fill no)
			(layer "F.CrtYd")
		)
		(fp_rect
			(start -0.508 0.9398)
			(end 0.508 -0.9398)
			(stroke
				(width 0)
				(type default)
			)
			(fill no)
			(layer "F.Fab")
		)
		(pad "1" smd custom
			(at 0 -0.4445 90)
			(size 0.1397 0.1397)
			(layers "F.Cu" "F.Mask" "F.Paste")
			(net "SW_PWR_R_HDD27")
			(options
				(clearance outline)
				(anchor circle)
			)
			(primitives
				(gr_poly
					(pts
						(arc
							(start -0.1778 -0.2794)
							(mid -0.249642 -0.249642)
							(end -0.2794 -0.1778)
						)
						(arc
							(start -0.2794 0.1778)
							(mid -0.249642 0.249642)
							(end -0.1778 0.2794)
						)
						(arc
							(start 0.1778 0.2794)
							(mid 0.249642 0.249642)
							(end 0.2794 0.1778)
						)
						(arc
							(start 0.2794 -0.1778)
							(mid 0.249642 -0.249642)
							(end 0.1778 -0.2794)
						)
					)
					(width 0)
					(fill yes)
				)
			)
		)
		(pad "2" smd custom
			(at 0 0.4445 90)
			(size 0.1397 0.1397)
			(layers "F.Cu" "F.Mask" "F.Paste")
			(net "GND")
			(options
				(clearance outline)
				(anchor circle)
			)
			(primitives
				(gr_poly
					(pts
						(arc
							(start -0.1778 -0.2794)
							(mid -0.249642 -0.249642)
							(end -0.2794 -0.1778)
						)
						(arc
							(start -0.2794 0.1778)
							(mid -0.249642 0.249642)
							(end -0.1778 0.2794)
						)
						(arc
							(start 0.1778 0.2794)
							(mid 0.249642 0.249642)
							(end 0.2794 0.1778)
						)
						(arc
							(start 0.2794 -0.1778)
							(mid 0.249642 -0.249642)
							(end 0.1778 -0.2794)
						)
					)
					(width 0)
					(fill yes)
				)
			)
		)
	)
	(footprint ""
		(layer "F.Cu")
		(at 231.4448 -386.715 90)
		(property "Reference" "U36"
			(at 0 0 90)
			(layer "F.SilkS")
			(hide yes)
			(effects
				(font
					(size 1.27 1.27)
				)
			)
		)
		(property "Value" "SN74LVC1G08DCKR-GP"
			(at -2.3368 -8.6868 90)
			(unlocked yes)
			(layer "F.Fab")
			(hide yes)
			(effects
				(font
					(size 1.016 1.016)
					(thickness 0.1524)
				)
			)
		)
		(property "Device Type" "SC70-5H44"
			(at -2.3114 -10.414 90)
			(unlocked yes)
			(layer "F.Fab")
			(hide yes)
			(effects
				(font
					(size 1.016 1.016)
					(thickness 0.1524)
				)
			)
		)
		(duplicate_pad_numbers_are_jumpers no)
		(fp_line
			(start 1.3843 -1.8034)
			(end 1.3843 -1.1176)
			(stroke
				(width 0.3302)
				(type default)
			)
			(layer "F.SilkS")
		)
		(fp_line
			(start 0.6604 -1.8034)
			(end 1.3843 -1.8034)
			(stroke
				(width 0.3302)
				(type default)
			)
			(layer "F.SilkS")
		)
		(fp_line
			(start 1.27 -1.7018)
			(end 1.27 1.7018)
			(stroke
				(width 0.1524)
				(type default)
			)
			(layer "F.SilkS")
		)
		(fp_line
			(start -1.27 -1.7018)
			(end 1.27 -1.7018)
			(stroke
				(width 0.1524)
				(type default)
			)
			(layer "F.SilkS")
		)
		(fp_line
			(start 1.27 1.7018)
			(end -1.27 1.7018)
			(stroke
				(width 0.1524)
				(type default)
			)
			(layer "F.SilkS")
		)
		(fp_line
			(start -1.27 1.7018)
			(end -1.27 -1.7018)
			(stroke
				(width 0.1524)
				(type default)
			)
			(layer "F.SilkS")
		)
		(fp_rect
			(start -1.524 1.9558)
			(end 1.524 -1.9558)
			(stroke
				(width 0)
				(type default)
			)
			(fill no)
			(layer "F.CrtYd")
		)
		(fp_poly
			(pts
				(xy -1.524 -1.9558) (xy 1.524 -1.9558) (xy 1.524 1.9558) (xy -1.524 1.9558)
			)
			(stroke
				(width 0)
				(type default)
			)
			(fill no)
			(layer "F.Fab")
		)
		(pad "1" smd rect
			(at 0.65024 -0.8255 90)
			(size 0.4064 1.2192)
			(layers "F.Cu" "F.Mask" "F.Paste")
			(net "P12V_IN_PGOOD")
		)
		(pad "2" smd rect
			(at 0 -0.8255 90)
			(size 0.4064 1.2192)
			(layers "F.Cu" "F.Mask" "F.Paste")
			(net "DPB_PWR_BTN_BUF_A")
		)
		(pad "3" smd rect
			(at -0.65024 -0.8255 90)
			(size 0.4064 1.2192)
			(layers "F.Cu" "F.Mask" "F.Paste")
			(net "GND")
		)
		(pad "4" smd rect
			(at -0.65024 0.8255 90)
			(size 0.4064 1.2192)
			(layers "F.Cu" "F.Mask" "F.Paste")
			(net "MB3_HS_ENABLE")
		)
		(pad "5" smd rect
			(at 0.65024 0.8255 90)
			(size 0.4064 1.2192)
			(layers "F.Cu" "F.Mask" "F.Paste")
			(net "P3V3_IN_BIAS")
		)
	)
	(footprint ""
		(layer "F.Cu")
		(at 146.630898 -48.554894 180)
		(property "Reference" "Q169"
			(at 0 0 180)
			(layer "F.SilkS")
			(hide yes)
			(effects
				(font
					(size 1.27 1.27)
				)
			)
		)
		(property "Value" "2N7002KDW-GP"
			(at -2.3622 -8.2042 180)
			(unlocked yes)
			(layer "F.Fab")
			(hide yes)
			(effects
				(font
					(size 1.016 1.016)
					(thickness 0.1524)
				)
			)
		)
		(property "Device Type" "SOT-363H44"
			(at -2.3622 -10.1092 180)
			(unlocked yes)
			(layer "F.Fab")
			(hide yes)
			(effects
				(font
					(size 1.016 1.016)
					(thickness 0.1524)
				)
			)
		)
		(duplicate_pad_numbers_are_jumpers no)
		(fp_line
			(start 1.4478 1.7018)
			(end 1.4478 -1.7018)
			(stroke
				(width 0.1524)
				(type default)
			)
			(layer "F.SilkS")
		)
		(fp_line
			(start 1.4478 -1.7018)
			(end -1.4478 -1.7018)
			(stroke
				(width 0.1524)
				(type default)
			)
			(layer "F.SilkS")
		)
		(fp_line
			(start -1.27 1.524)
			(end -1.27 0.6604)
			(stroke
				(width 0.4826)
				(type default)
			)
			(layer "F.SilkS")
		)
		(fp_line
			(start -1.4478 1.7018)
			(end 1.4478 1.7018)
			(stroke
				(width 0.1524)
				(type default)
			)
			(layer "F.SilkS")
		)
		(fp_line
			(start -1.4478 -1.7018)
			(end -1.4478 1.7018)
			(stroke
				(width 0.1524)
				(type default)
			)
			(layer "F.SilkS")
		)
		(fp_poly
			(pts
				(xy -1.524 -1.778) (xy 1.524 -1.778) (xy 1.524 1.778) (xy -1.524 1.778)
			)
			(stroke
				(width 0)
				(type default)
			)
			(fill no)
			(layer "F.CrtYd")
		)
		(fp_poly
			(pts
				(xy -1.524 -1.778) (xy 1.524 -1.778) (xy 1.524 1.778) (xy -1.524 1.778)
			)
			(stroke
				(width 0)
				(type default)
			)
			(fill no)
			(layer "F.Fab")
		)
		(pad "1" smd rect
			(at -0.65024 0.9398 180)
			(size 0.4064 1.016)
			(layers "F.Cu" "F.Mask" "F.Paste")
			(net "GND")
		)
		(pad "2" smd rect
			(at 0 0.9398 180)
			(size 0.4064 1.016)
			(layers "F.Cu" "F.Mask" "F.Paste")
			(net "SW_PWR_R_HDD28")
		)
		(pad "3" smd rect
			(at 0.65024 0.9398 180)
			(size 0.4064 1.016)
			(layers "F.Cu" "F.Mask" "F.Paste")
			(net "SW_HDD_P28")
		)
		(pad "4" smd rect
			(at 0.65024 -0.9398 180)
			(size 0.4064 1.016)
			(layers "F.Cu" "F.Mask" "F.Paste")
			(net "GND")
		)
		(pad "5" smd rect
			(at 0 -0.9398 180)
			(size 0.4064 1.016)
			(layers "F.Cu" "F.Mask" "F.Paste")
			(net "SW_HDD_G28")
		)
		(pad "6" smd rect
			(at -0.65024 -0.9398 180)
			(size 0.4064 1.016)
			(layers "F.Cu" "F.Mask" "F.Paste")
			(net "SW_HDD_R28")
		)
	)
	(footprint ""
		(layer "F.Cu")
		(at 178.435 -170.285918 180)
		(property "Reference" "Q101"
			(at 0 0 180)
			(layer "F.SilkS")
			(hide yes)
			(effects
				(font
					(size 1.27 1.27)
				)
			)
		)
		(property "Value" "AO4406AL-GP"
			(at -3.707384 -1.5367 180)
			(unlocked yes)
			(layer "F.Fab")
			(hide yes)
			(effects
				(font
					(size 1.016 1.016)
					(thickness 0.1524)
				)
			)
		)
		(property "Device Type" "SOIC8H69"
			(at -3.707384 -3.0607 180)
			(unlocked yes)
			(layer "F.Fab")
			(hide yes)
			(effects
				(font
					(size 1.016 1.016)
					(thickness 0.1524)
				)
			)
		)
		(duplicate_pad_numbers_are_jumpers no)
		(fp_line
			(start 2.1336 1.4224)
			(end 2.1336 -1.4224)
			(stroke
				(width 0.1524)
				(type default)
			)
			(layer "F.SilkS")
		)
		(fp_line
			(start 2.1336 -1.4224)
			(end -2.7432 -1.4224)
			(stroke
				(width 0.1524)
				(type default)
			)
			(layer "F.SilkS")
		)
		(fp_line
			(start -2.1844 -0.0508)
			(end -2.7178 0.508)
			(stroke
				(width 0.1524)
				(type default)
			)
			(layer "F.SilkS")
		)
		(fp_line
			(start -2.6289 3.4417)
			(end -2.6289 1.4732)
			(stroke
				(width 0.381)
				(type default)
			)
			(layer "F.SilkS")
		)
		(fp_line
			(start -2.7178 -0.508)
			(end -2.1844 -0.0508)
			(stroke
				(width 0.1524)
				(type default)
			)
			(layer "F.SilkS")
		)
		(fp_line
			(start -2.7432 1.4224)
			(end 2.1336 1.4224)
			(stroke
				(width 0.1524)
				(type default)
			)
			(layer "F.SilkS")
		)
		(fp_line
			(start -2.7432 1.4224)
			(end -2.6416 1.4224)
			(stroke
				(width 0.1524)
				(type default)
			)
			(layer "F.SilkS")
		)
		(fp_line
			(start -2.7432 -1.4224)
			(end -2.7432 1.4224)
			(stroke
				(width 0.1524)
				(type default)
			)
			(layer "F.SilkS")
		)
		(fp_poly
			(pts
				(xy -2.2098 -1.4224) (xy -2.2098 1.4224) (xy 2.2098 1.4224) (xy 2.2098 -1.4224)
			)
			(stroke
				(width 0)
				(type default)
			)
			(fill yes)
			(layer "F.SilkS")
		)
		(fp_rect
			(start -2.450084 2.999994)
			(end 2.450084 -2.999994)
			(stroke
				(width 0)
				(type default)
			)
			(fill no)
			(layer "F.CrtYd")
		)
		(fp_poly
			(pts
				(xy -2.8194 3.6322) (xy -2.8194 -3.6322) (xy 2.8194 -3.6322) (xy 2.8194 1.18364) (xy 2.450084 1.18364)
				(xy 2.450084 -2.999994) (xy -2.450084 -2.999994) (xy -2.450084 2.999994) (xy 2.450084 2.999994)
				(xy 2.450084 1.18618) (xy 2.8194 1.18618) (xy 2.8194 3.6322)
			)
			(stroke
				(width 0)
				(type default)
			)
			(fill no)
			(layer "F.CrtYd")
		)
		(fp_rect
			(start -2.8194 3.6322)
			(end 2.8194 -3.6322)
			(stroke
				(width 0)
				(type default)
			)
			(fill no)
			(layer "F.Fab")
		)
		(pad "1" smd rect
			(at -1.905 2.54 180)
			(size 0.635 1.651)
			(layers "F.Cu" "F.Mask" "F.Paste")
			(net "P5V_HDD17")
		)
		(pad "2" smd rect
			(at -0.635 2.54 180)
			(size 0.635 1.651)
			(layers "F.Cu" "F.Mask" "F.Paste")
			(net "P5V_HDD17")
		)
		(pad "3" smd rect
			(at 0.635 2.54 180)
			(size 0.635 1.651)
			(layers "F.Cu" "F.Mask" "F.Paste")
			(net "P5V_HDD17")
		)
		(pad "4" smd rect
			(at 1.905 2.54 180)
			(size 0.635 1.651)
			(layers "F.Cu" "F.Mask" "F.Paste")
			(net "SW_HDD_P17")
		)
		(pad "5" smd rect
			(at 1.905 -2.54 180)
			(size 0.635 1.651)
			(layers "F.Cu" "F.Mask" "F.Paste")
			(net "P5V_A_2")
		)
		(pad "6" smd rect
			(at 0.635 -2.54 180)
			(size 0.635 1.651)
			(layers "F.Cu" "F.Mask" "F.Paste")
			(net "P5V_A_2")
		)
		(pad "7" smd rect
			(at -0.635 -2.54 180)
			(size 0.635 1.651)
			(layers "F.Cu" "F.Mask" "F.Paste")
			(net "P5V_A_2")
		)
		(pad "8" smd rect
			(at -1.905 -2.54 180)
			(size 0.635 1.651)
			(layers "F.Cu" "F.Mask" "F.Paste")
			(net "P5V_A_2")
		)
	)
)
